(kicad_pcb
	(version 20260206)
	(generator "pcbnew")
	(generator_version "10.0")
	(general
		(thickness 1.6)
		(legacy_teardrops no)
	)
	(paper "A4")
	(title_block
		(title "Bryce Canyon_IOM_M2_16342-2_OCP.brd")
		(comment 1 "Bryce Canyon / footprints 448-455 of 1146")
	)
	(layers
		(0 "F.Cu" signal "TOP")
		(4 "In1.Cu" signal "L2GND")
		(6 "In2.Cu" signal "L3")
		(8 "In3.Cu" signal "L4VCC")
		(10 "In4.Cu" signal "L5VCC")
		(12 "In5.Cu" signal "L6")
		(14 "In6.Cu" signal "L7GND")
		(2 "B.Cu" signal "BOTTOM")
		(9 "F.Adhes" user "F.Adhesive")
		(11 "B.Adhes" user "B.Adhesive")
		(13 "F.Paste" user "Package Geometry/Pastemask Top")
		(15 "B.Paste" user "Package Geometry/Pastemask Bottom")
		(5 "F.SilkS" user "Ref Des/Silkscreen Top")
		(7 "B.SilkS" user "Ref Des/Silkscreen Bottom")
		(1 "F.Mask" user "Board Geometry/Soldermask Top")
		(3 "B.Mask" user "Board Geometry/Soldermask Bottom")
		(17 "Dwgs.User" user "User.Drawings")
		(19 "Cmts.User" user "User.Comments")
		(21 "Eco1.User" user "User.Eco1")
		(23 "Eco2.User" user "User.Eco2")
		(25 "Edge.Cuts" user "Board Geometry/Outline")
		(27 "Margin" user)
		(31 "F.CrtYd" user "Package Geometry/Place Bound Top")
		(29 "B.CrtYd" user "Package Geometry/Place Bound Bottom")
		(35 "F.Fab" user "Ref Des/Assembly Top")
		(33 "B.Fab" user "Ref Des/Assembly Bottom")
	)
	(footprint ""
		(layer "F.Cu")
		(at 87.3506 -170.688 90)
		(property "Reference" "R726"
			(at 0 0 90)
			(layer "F.SilkS")
			(hide yes)
			(effects
				(font
					(size 1.27 1.27)
				)
			)
		)
		(property "Value" "4K7R2F-GP"
			(at 0.064008 -3.993896 90)
			(unlocked yes)
			(layer "F.Fab")
			(hide yes)
			(effects
				(font
					(size 1.016 1.016)
					(thickness 0.1524)
				)
			)
		)
		(property "Device Type" "R402H16"
			(at 0.064008 -5.517896 90)
			(unlocked yes)
			(layer "F.Fab")
			(hide yes)
			(effects
				(font
					(size 1.016 1.016)
					(thickness 0.1524)
				)
			)
		)
		(duplicate_pad_numbers_are_jumpers no)
		(fp_line
			(start 0.508 -0.9398)
			(end -0.508 -0.9398)
			(stroke
				(width 0.1524)
				(type default)
			)
			(layer "F.SilkS")
		)
		(fp_line
			(start -0.508 -0.9398)
			(end -0.508 0.9398)
			(stroke
				(width 0.1524)
				(type default)
			)
			(layer "F.SilkS")
		)
		(fp_rect
			(start -0.508 0.9398)
			(end 0.508 -0.9398)
			(stroke
				(width 0)
				(type default)
			)
			(fill no)
			(layer "F.CrtYd")
		)
		(fp_rect
			(start -0.508 0.9398)
			(end 0.508 -0.9398)
			(stroke
				(width 0)
				(type default)
			)
			(fill no)
			(layer "F.Fab")
		)
		(pad "1" smd custom
			(at 0 -0.4445 90)
			(size 0.1397 0.1397)
			(layers "F.Cu" "F.Mask" "F.Paste")
			(net "P3V3_STBY")
			(options
				(clearance outline)
				(anchor circle)
			)
			(primitives
				(gr_poly
					(pts
						(arc
							(start -0.1778 -0.2794)
							(mid -0.249642 -0.249642)
							(end -0.2794 -0.1778)
						)
						(arc
							(start -0.2794 0.1778)
							(mid -0.249642 0.249642)
							(end -0.1778 0.2794)
						)
						(arc
							(start 0.1778 0.2794)
							(mid 0.249642 0.249642)
							(end 0.2794 0.1778)
						)
						(arc
							(start 0.2794 -0.1778)
							(mid 0.249642 -0.249642)
							(end 0.1778 -0.2794)
						)
					)
					(width 0)
					(fill yes)
				)
			)
		)
		(pad "2" smd custom
			(at 0 0.4445 90)
			(size 0.1397 0.1397)
			(layers "F.Cu" "F.Mask" "F.Paste")
			(net "IOM_STBY_PGOOD")
			(options
				(clearance outline)
				(anchor circle)
			)
			(primitives
				(gr_poly
					(pts
						(arc
							(start -0.1778 -0.2794)
							(mid -0.249642 -0.249642)
							(end -0.2794 -0.1778)
						)
						(arc
							(start -0.2794 0.1778)
							(mid -0.249642 0.249642)
							(end -0.1778 0.2794)
						)
						(arc
							(start 0.1778 0.2794)
							(mid 0.249642 0.249642)
							(end 0.2794 0.1778)
						)
						(arc
							(start 0.2794 -0.1778)
							(mid 0.249642 -0.249642)
							(end 0.1778 -0.2794)
						)
					)
					(width 0)
					(fill yes)
				)
			)
		)
	)
	(footprint ""
		(layer "F.Cu")
		(at 93.09989 -52.526946)
		(property "Reference" "U38"
			(at 0 0 0)
			(layer "F.SilkS")
			(hide yes)
			(effects
				(font
					(size 1.27 1.27)
				)
			)
		)
		(property "Value" "SN74LVC1G08DCKR-GP"
			(at -2.3368 -8.6868 0)
			(unlocked yes)
			(layer "F.Fab")
			(hide yes)
			(effects
				(font
					(size 1.016 1.016)
					(thickness 0.1524)
				)
			)
		)
		(property "Device Type" "SC70-5H44"
			(at -2.3114 -10.414 0)
			(unlocked yes)
			(layer "F.Fab")
			(hide yes)
			(effects
				(font
					(size 1.016 1.016)
					(thickness 0.1524)
				)
			)
		)
		(duplicate_pad_numbers_are_jumpers no)
		(fp_line
			(start -1.27 -1.7018)
			(end 1.27 -1.7018)
			(stroke
				(width 0.1524)
				(type default)
			)
			(layer "F.SilkS")
		)
		(fp_line
			(start -1.27 1.7018)
			(end -1.27 -1.7018)
			(stroke
				(width 0.1524)
				(type default)
			)
			(layer "F.SilkS")
		)
		(fp_line
			(start 0.6604 -1.8034)
			(end 1.3843 -1.8034)
			(stroke
				(width 0.3302)
				(type default)
			)
			(layer "F.SilkS")
		)
		(fp_line
			(start 1.27 -1.7018)
			(end 1.27 1.7018)
			(stroke
				(width 0.1524)
				(type default)
			)
			(layer "F.SilkS")
		)
		(fp_line
			(start 1.27 1.7018)
			(end -1.27 1.7018)
			(stroke
				(width 0.1524)
				(type default)
			)
			(layer "F.SilkS")
		)
		(fp_line
			(start 1.3843 -1.8034)
			(end 1.3843 -1.1176)
			(stroke
				(width 0.3302)
				(type default)
			)
			(layer "F.SilkS")
		)
		(fp_rect
			(start -1.524 1.9558)
			(end 1.524 -1.9558)
			(stroke
				(width 0)
				(type default)
			)
			(fill no)
			(layer "F.CrtYd")
		)
		(fp_poly
			(pts
				(xy -1.524 -1.9558) (xy 1.524 -1.9558) (xy 1.524 1.9558) (xy -1.524 1.9558)
			)
			(stroke
				(width 0)
				(type default)
			)
			(fill no)
			(layer "F.Fab")
		)
		(pad "1" smd rect
			(at 0.65024 -0.8255)
			(size 0.4064 1.2192)
			(layers "F.Cu" "F.Mask" "F.Paste")
			(net "IOM_FULL_PWR_EN")
		)
		(pad "2" smd rect
			(at 0 -0.8255)
			(size 0.4064 1.2192)
			(layers "F.Cu" "F.Mask" "F.Paste")
			(net "IOM_STBY_PGOOD")
		)
		(pad "3" smd rect
			(at -0.65024 -0.8255)
			(size 0.4064 1.2192)
			(layers "F.Cu" "F.Mask" "F.Paste")
			(net "GND")
		)
		(pad "4" smd rect
			(at -0.65024 0.8255)
			(size 0.4064 1.2192)
			(layers "F.Cu" "F.Mask" "F.Paste")
			(net "P3V3_EN")
		)
		(pad "5" smd rect
			(at 0.65024 0.8255)
			(size 0.4064 1.2192)
			(layers "F.Cu" "F.Mask" "F.Paste")
			(net "P3V3_STBY")
		)
	)
	(footprint ""
		(layer "F.Cu")
		(at 82.441796 -175.76038 90)
		(property "Reference" "C191"
			(at 0 0 90)
			(layer "F.SilkS")
			(hide yes)
			(effects
				(font
					(size 1.27 1.27)
				)
			)
		)
		(property "Value" "SC10U6D3V5KX-4GP"
			(at -0.0762 -6.1214 90)
			(unlocked yes)
			(layer "F.Fab")
			(hide yes)
			(effects
				(font
					(size 1.016 1.016)
					(thickness 0.1524)
				)
			)
		)
		(property "Device Type" "C805H58"
			(at -0.0762 -8.1534 90)
			(unlocked yes)
			(layer "F.Fab")
			(hide yes)
			(effects
				(font
					(size 1.016 1.016)
					(thickness 0.1524)
				)
			)
		)
		(duplicate_pad_numbers_are_jumpers no)
		(fp_line
			(start 0.635 0)
			(end -0.635 0)
			(stroke
				(width 0.508)
				(type default)
			)
			(layer "F.SilkS")
		)
		(fp_rect
			(start -0.9652 1.778)
			(end 0.9652 -1.778)
			(stroke
				(width 0)
				(type default)
			)
			(fill no)
			(layer "F.CrtYd")
		)
		(fp_poly
			(pts
				(xy -0.9652 -1.778) (xy 0.9652 -1.778) (xy 0.9652 1.778) (xy -0.9652 1.778)
			)
			(stroke
				(width 0)
				(type default)
			)
			(fill no)
			(layer "F.Fab")
		)
		(pad "1" smd rect
			(at 0 -0.9652 90)
			(size 1.397 1.143)
			(layers "F.Cu" "F.Mask" "F.Paste")
			(net "TPS74801_P2V5_STBY_OUT")
		)
		(pad "2" smd rect
			(at 0 0.9652 90)
			(size 1.397 1.143)
			(layers "F.Cu" "F.Mask" "F.Paste")
			(net "GND")
		)
	)
	(footprint ""
		(layer "F.Cu")
		(at 200.3552 -107.3912 -90)
		(property "Reference" "C602"
			(at 0 0 270)
			(layer "F.SilkS")
			(hide yes)
			(effects
				(font
					(size 1.27 1.27)
				)
			)
		)
		(property "Value" "SCD1U16V2KX-3GP"
			(at 1.1811 -2.7051 270)
			(unlocked yes)
			(layer "F.Fab")
			(hide yes)
			(effects
				(font
					(size 1.016 1.016)
					(thickness 0.1524)
				)
			)
		)
		(property "Device Type" "C402H22"
			(at 1.1811 -4.2291 270)
			(unlocked yes)
			(layer "F.Fab")
			(hide yes)
			(effects
				(font
					(size 1.016 1.016)
					(thickness 0.1524)
				)
			)
		)
		(duplicate_pad_numbers_are_jumpers no)
		(fp_rect
			(start -0.4318 0.9525)
			(end 0.4318 -0.9525)
			(stroke
				(width 0)
				(type default)
			)
			(fill no)
			(layer "F.CrtYd")
		)
		(fp_rect
			(start -0.4318 0.9525)
			(end 0.4318 -0.9525)
			(stroke
				(width 0)
				(type default)
			)
			(fill no)
			(layer "F.Fab")
		)
		(pad "1" smd custom
			(at 0 -0.4445 270)
			(size 0.1524 0.1524)
			(layers "F.Cu" "F.Mask" "F.Paste")
			(net "P3V3_STBY")
			(options
				(clearance outline)
				(anchor circle)
			)
			(primitives
				(gr_poly
					(pts
						(arc
							(start 0.3048 -0.2032)
							(mid 0.275042 -0.275042)
							(end 0.2032 -0.3048)
						)
						(arc
							(start -0.2032 -0.3048)
							(mid -0.275042 -0.275042)
							(end -0.3048 -0.2032)
						)
						(arc
							(start -0.3048 0.2032)
							(mid -0.275042 0.275042)
							(end -0.2032 0.3048)
						)
						(arc
							(start 0.2032 0.3048)
							(mid 0.275042 0.275042)
							(end 0.3048 0.2032)
						)
					)
					(width 0)
					(fill yes)
				)
			)
		)
		(pad "2" smd custom
			(at 0 0.4445 270)
			(size 0.1524 0.1524)
			(layers "F.Cu" "F.Mask" "F.Paste")
			(net "GND")
			(options
				(clearance outline)
				(anchor circle)
			)
			(primitives
				(gr_poly
					(pts
						(arc
							(start 0.3048 -0.2032)
							(mid 0.275042 -0.275042)
							(end 0.2032 -0.3048)
						)
						(arc
							(start -0.2032 -0.3048)
							(mid -0.275042 -0.275042)
							(end -0.3048 -0.2032)
						)
						(arc
							(start -0.3048 0.2032)
							(mid -0.275042 0.275042)
							(end -0.2032 0.3048)
						)
						(arc
							(start 0.2032 0.3048)
							(mid 0.275042 0.275042)
							(end 0.3048 0.2032)
						)
					)
					(width 0)
					(fill yes)
				)
			)
		)
	)
	(footprint ""
		(layer "F.Cu")
		(at 119.528844 -13.467588 90)
		(property "Reference" "C133"
			(at 0 0 90)
			(layer "F.SilkS")
			(hide yes)
			(effects
				(font
					(size 1.27 1.27)
				)
			)
		)
		(property "Value" "SCD015U25V2KX-GP"
			(at 1.1811 -2.7051 90)
			(unlocked yes)
			(layer "F.Fab")
			(hide yes)
			(effects
				(font
					(size 1.016 1.016)
					(thickness 0.1524)
				)
			)
		)
		(property "Device Type" "C402H22"
			(at 1.1811 -4.2291 90)
			(unlocked yes)
			(layer "F.Fab")
			(hide yes)
			(effects
				(font
					(size 1.016 1.016)
					(thickness 0.1524)
				)
			)
		)
		(duplicate_pad_numbers_are_jumpers no)
		(fp_rect
			(start -0.4318 0.9525)
			(end 0.4318 -0.9525)
			(stroke
				(width 0)
				(type default)
			)
			(fill no)
			(layer "F.CrtYd")
		)
		(fp_rect
			(start -0.4318 0.9525)
			(end 0.4318 -0.9525)
			(stroke
				(width 0)
				(type default)
			)
			(fill no)
			(layer "F.Fab")
		)
		(pad "1" smd custom
			(at 0 -0.4445 90)
			(size 0.1524 0.1524)
			(layers "F.Cu" "F.Mask" "F.Paste")
			(net "MB0_CM_SENSE_P")
			(options
				(clearance outline)
				(anchor circle)
			)
			(primitives
				(gr_poly
					(pts
						(arc
							(start 0.3048 -0.2032)
							(mid 0.275042 -0.275042)
							(end 0.2032 -0.3048)
						)
						(arc
							(start -0.2032 -0.3048)
							(mid -0.275042 -0.275042)
							(end -0.3048 -0.2032)
						)
						(arc
							(start -0.3048 0.2032)
							(mid -0.275042 0.275042)
							(end -0.2032 0.3048)
						)
						(arc
							(start 0.2032 0.3048)
							(mid 0.275042 0.275042)
							(end 0.3048 0.2032)
						)
					)
					(width 0)
					(fill yes)
				)
			)
		)
		(pad "2" smd custom
			(at 0 0.4445 90)
			(size 0.1524 0.1524)
			(layers "F.Cu" "F.Mask" "F.Paste")
			(net "MB0_CM_SENSE_N")
			(options
				(clearance outline)
				(anchor circle)
			)
			(primitives
				(gr_poly
					(pts
						(arc
							(start 0.3048 -0.2032)
							(mid 0.275042 -0.275042)
							(end 0.2032 -0.3048)
						)
						(arc
							(start -0.2032 -0.3048)
							(mid -0.275042 -0.275042)
							(end -0.3048 -0.2032)
						)
						(arc
							(start -0.3048 0.2032)
							(mid -0.275042 0.275042)
							(end -0.2032 0.3048)
						)
						(arc
							(start 0.2032 0.3048)
							(mid 0.275042 0.275042)
							(end 0.3048 0.2032)
						)
					)
					(width 0)
					(fill yes)
				)
			)
		)
	)
	(footprint ""
		(layer "F.Cu")
		(at 183.460644 -132.973826 180)
		(property "Reference" "VIA67"
			(at 0 0 180)
			(layer "F.SilkS")
			(hide yes)
			(effects
				(font
					(size 1.27 1.27)
				)
			)
		)
		(property "Value" "85OHM-8L-1D6MM-L16L18-GP"
			(at 4.064 0.6096 180)
			(unlocked yes)
			(layer "F.Fab")
			(hide yes)
			(effects
				(font
					(size 1.016 1.016)
					(thickness 0.1524)
				)
			)
		)
		(property "Device Type" "VIA-PCIE-4P-368076"
			(at 4.064 -0.9144 180)
			(unlocked yes)
			(layer "F.Fab")
			(hide yes)
			(effects
				(font
					(size 1.016 1.016)
					(thickness 0.1524)
				)
			)
		)
		(duplicate_pad_numbers_are_jumpers no)
		(fp_rect
			(start -1.8415 0.381)
			(end 1.8415 -0.381)
			(stroke
				(width 0)
				(type default)
			)
			(fill no)
			(layer "F.CrtYd")
		)
		(fp_rect
			(start -1.8415 0.381)
			(end 1.8415 -0.381)
			(stroke
				(width 0)
				(type default)
			)
			(fill no)
			(layer "F.Fab")
		)
		(pad "1" thru_hole circle
			(at -1.4605 0 180)
			(size 0.508 0.508)
			(drill 0.254)
			(layers "*.Cu" "*.Mask")
			(remove_unused_layers no)
			(net "GND")
			(clearance 0.127)
			(thermal_gap 0.127)
		)
		(pad "2" thru_hole circle
			(at -0.4445 0 180)
			(size 0.508 0.508)
			(drill 0.254)
			(layers "*.Cu" "*.Mask")
			(remove_unused_layers no)
			(net "PCIE_COMP_TO_IOM_CLK_3_DP")
			(clearance 0.127)
			(thermal_gap 0.127)
		)
		(pad "3" thru_hole circle
			(at 0.4445 0 180)
			(size 0.508 0.508)
			(drill 0.254)
			(layers "*.Cu" "*.Mask")
			(remove_unused_layers no)
			(net "PCIE_COMP_TO_IOM_CLK_3_DN")
			(clearance 0.127)
			(thermal_gap 0.127)
		)
		(pad "4" thru_hole circle
			(at 1.4605 0 180)
			(size 0.508 0.508)
			(drill 0.254)
			(layers "*.Cu" "*.Mask")
			(remove_unused_layers no)
			(net "GND")
			(clearance 0.127)
			(thermal_gap 0.127)
		)
	)
	(footprint ""
		(layer "F.Cu")
		(at 42.1132 -158.4198)
		(property "Reference" "TP186"
			(at 0 0 0)
			(layer "F.SilkS")
			(hide yes)
			(effects
				(font
					(size 1.27 1.27)
				)
			)
		)
		(property "Value" "TPAD28-2-GP"
			(at -0.0127 -1.6637 0)
			(unlocked yes)
			(layer "F.Fab")
			(hide yes)
			(effects
				(font
					(size 1.016 1.016)
					(thickness 0.1524)
				)
			)
		)
		(property "Device Type" "TPAD28"
			(at -0.0127 -3.1877 0)
			(unlocked yes)
			(layer "F.Fab")
			(hide yes)
			(effects
				(font
					(size 1.016 1.016)
					(thickness 0.1524)
				)
			)
		)
		(duplicate_pad_numbers_are_jumpers no)
		(fp_poly
			(pts
				(arc
					(start 0.3556 0)
					(mid -0.3556 0)
					(end 0.3556 0)
				)
			)
			(stroke
				(width 0)
				(type default)
			)
			(fill no)
			(layer "F.CrtYd")
		)
		(fp_poly
			(pts
				(arc
					(start 0.6096 0)
					(mid -0.6096 0)
					(end 0.6096 0)
				)
			)
			(stroke
				(width 0)
				(type default)
			)
			(fill no)
			(layer "F.Fab")
		)
		(pad "1" smd circle
			(at 0 0)
			(size 0.7112 0.7112)
			(layers "F.Cu" "F.Mask" "F.Paste")
			(net "TP_BMC_GPIOL0")
		)
	)
	(footprint ""
		(layer "F.Cu")
		(at 22.011386 -131.007358 180)
		(property "Reference" "R144"
			(at 0 0 180)
			(layer "F.SilkS")
			(hide yes)
			(effects
				(font
					(size 1.27 1.27)
				)
			)
		)
		(property "Value" "4K7R2F-GP"
			(at 0.064008 -3.993896 180)
			(unlocked yes)
			(layer "F.Fab")
			(hide yes)
			(effects
				(font
					(size 1.016 1.016)
					(thickness 0.1524)
				)
			)
		)
		(property "Device Type" "R402H16"
			(at 0.064008 -5.517896 180)
			(unlocked yes)
			(layer "F.Fab")
			(hide yes)
			(effects
				(font
					(size 1.016 1.016)
					(thickness 0.1524)
				)
			)
		)
		(duplicate_pad_numbers_are_jumpers no)
		(fp_line
			(start 0.508 -0.9398)
			(end -0.508 -0.9398)
			(stroke
				(width 0.1524)
				(type default)
			)
			(layer "F.SilkS")
		)
		(fp_line
			(start -0.508 -0.9398)
			(end -0.508 0.9398)
			(stroke
				(width 0.1524)
				(type default)
			)
			(layer "F.SilkS")
		)
		(fp_rect
			(start -0.508 0.9398)
			(end 0.508 -0.9398)
			(stroke
				(width 0)
				(type default)
			)
			(fill no)
			(layer "F.CrtYd")
		)
		(fp_rect
			(start -0.508 0.9398)
			(end 0.508 -0.9398)
			(stroke
				(width 0)
				(type default)
			)
			(fill no)
			(layer "F.Fab")
		)
		(pad "1" smd custom
			(at 0 -0.4445 180)
			(size 0.1397 0.1397)
			(layers "F.Cu" "F.Mask" "F.Paste")
			(net "DDR4_ALERT")
			(options
				(clearance outline)
				(anchor circle)
			)
			(primitives
				(gr_poly
					(pts
						(arc
							(start -0.1778 -0.2794)
							(mid -0.249642 -0.249642)
							(end -0.2794 -0.1778)
						)
						(arc
							(start -0.2794 0.1778)
							(mid -0.249642 0.249642)
							(end -0.1778 0.2794)
						)
						(arc
							(start 0.1778 0.2794)
							(mid 0.249642 0.249642)
							(end 0.2794 0.1778)
						)
						(arc
							(start 0.2794 -0.1778)
							(mid 0.249642 -0.249642)
							(end 0.1778 -0.2794)
						)
					)
					(width 0)
					(fill yes)
				)
			)
		)
		(pad "2" smd custom
			(at 0 0.4445 180)
			(size 0.1397 0.1397)
			(layers "F.Cu" "F.Mask" "F.Paste")
			(net "P1V2_STBY")
			(options
				(clearance outline)
				(anchor circle)
			)
			(primitives
				(gr_poly
					(pts
						(arc
							(start -0.1778 -0.2794)
							(mid -0.249642 -0.249642)
							(end -0.2794 -0.1778)
						)
						(arc
							(start -0.2794 0.1778)
							(mid -0.249642 0.249642)
							(end -0.1778 0.2794)
						)
						(arc
							(start 0.1778 0.2794)
							(mid 0.249642 0.249642)
							(end 0.2794 0.1778)
						)
						(arc
							(start 0.2794 -0.1778)
							(mid 0.249642 -0.249642)
							(end 0.1778 -0.2794)
						)
					)
					(width 0)
					(fill yes)
				)
			)
		)
	)
)
